(kicad_pcb
	(version 20260206)
	(generator "pcbnew")
	(generator_version "10.0")
	(general
		(thickness 1.6)
		(legacy_teardrops no)
	)
	(paper "A4")
	(title_block
		(title "04192023_DAF0TMB3IC0_F0TG_MB_C_brd_V02_OCP.brd")
		(comment 1 "Grand Teton / footprints 2353-2358 of 8354")
	)
	(layers
		(0 "F.Cu" signal "TOP")
		(4 "In1.Cu" signal "GND")
		(6 "In2.Cu" signal "IN1")
		(8 "In3.Cu" signal "GND1")
		(10 "In4.Cu" signal "IN2")
		(12 "In5.Cu" signal "GND2")
		(14 "In6.Cu" signal "IN3")
		(16 "In7.Cu" signal "GND3")
		(18 "In8.Cu" signal "VCC")
		(20 "In9.Cu" signal "VCC1")
		(22 "In10.Cu" signal "GND4")
		(24 "In11.Cu" signal "IN4")
		(26 "In12.Cu" signal "GND5")
		(28 "In13.Cu" signal "IN5")
		(30 "In14.Cu" signal "GND6")
		(32 "In15.Cu" signal "IN6")
		(34 "In16.Cu" signal "GND7")
		(2 "B.Cu" signal "BOTTOM")
		(9 "F.Adhes" user "F.Adhesive")
		(11 "B.Adhes" user "B.Adhesive")
		(13 "F.Paste" user "Package Geometry/Pastemask Top")
		(15 "B.Paste" user "Package Geometry/Pastemask Bottom")
		(5 "F.SilkS" user "Ref Des/Silkscreen Top")
		(7 "B.SilkS" user "Ref Des/Silkscreen Bottom")
		(1 "F.Mask" user "Board Geometry/Soldermask Top")
		(3 "B.Mask" user "Board Geometry/Soldermask Bottom")
		(17 "Dwgs.User" user "User.Drawings")
		(19 "Cmts.User" user "User.Comments")
		(21 "Eco1.User" user "User.Eco1")
		(23 "Eco2.User" user "User.Eco2")
		(25 "Edge.Cuts" user "Board Geometry/Outline")
		(27 "Margin" user)
		(31 "F.CrtYd" user "Package Geometry/Place Bound Top")
		(29 "B.CrtYd" user "Package Geometry/Place Bound Bottom")
		(35 "F.Fab" user "Ref Des/Assembly Top")
		(33 "B.Fab" user "Ref Des/Assembly Bottom")
	)
	(footprint ""
		(layer "F.Cu")
		(at 511.924808 7.571994 -90)
		(property "Reference" "X8002"
			(at -1.835658 4.818888 0)
			(unlocked yes)
			(layer "F.SilkS")
			(effects
				(font
					(size 0.7874 0.5842)
					(thickness 0.1524)
				)
				(justify left)
			)
		)
		(property "Value" ""
			(at 0 0 270)
			(layer "F.Fab")
			(effects
				(font
					(size 1.27 1.27)
				)
			)
		)
		(property "Device Type" "TP_TDR_4P_FTS_TH-TP_TDR_4P_DIP,EMPTY,TP15"
			(at 1.30175 1.27 0)
			(unlocked yes)
			(layer "F.Fab")
			(hide yes)
			(effects
				(font
					(size 0.635 0.4064)
					(thickness 0.1524)
				)
			)
		)
		(property "User Part Number" "N_A"
			(at 1.30175 1.27 0)
			(unlocked yes)
			(layer "Cmts.User")
			(hide yes)
			(effects
				(font
					(size 0.635 0.4064)
					(thickness 0.1524)
				)
			)
		)
		(duplicate_pad_numbers_are_jumpers no)
		(fp_line
			(start 0 3.81)
			(end 2.54 3.81)
			(stroke
				(width 0.1524)
				(type default)
			)
			(layer "F.SilkS")
		)
		(fp_line
			(start 2.54 3.81)
			(end 2.54 3.6703)
			(stroke
				(width 0.1524)
				(type default)
			)
			(layer "F.SilkS")
		)
		(fp_line
			(start 0 3.175)
			(end 0 3.81)
			(stroke
				(width 0.1524)
				(type default)
			)
			(layer "F.SilkS")
		)
		(fp_line
			(start 2.54 1.4097)
			(end 2.54 1.1303)
			(stroke
				(width 0.1524)
				(type default)
			)
			(layer "F.SilkS")
		)
		(fp_line
			(start 0 0.635)
			(end 0 1.905)
			(stroke
				(width 0.1524)
				(type default)
			)
			(layer "F.SilkS")
		)
		(fp_line
			(start 2.54 -1.1303)
			(end 2.54 -1.27)
			(stroke
				(width 0.1524)
				(type default)
			)
			(layer "F.SilkS")
		)
		(fp_line
			(start 0 -1.27)
			(end 0 -0.635)
			(stroke
				(width 0.1524)
				(type default)
			)
			(layer "F.SilkS")
		)
		(fp_line
			(start 2.54 -1.27)
			(end 0 -1.27)
			(stroke
				(width 0.1524)
				(type default)
			)
			(layer "F.SilkS")
		)
		(fp_poly
			(pts
				(xy -2.285746 -0.762) (xy -0.761746 0) (xy -2.285746 0.762)
			)
			(stroke
				(width 0)
				(type default)
			)
			(fill yes)
			(layer "F.SilkS")
		)
		(fp_line
			(start 0 3.81)
			(end 2.54 3.81)
			(stroke
				(width 0.1)
				(type default)
			)
			(layer "F.Fab")
		)
		(fp_line
			(start 2.54 3.81)
			(end 2.54 -1.27)
			(stroke
				(width 0.1)
				(type default)
			)
			(layer "F.Fab")
		)
		(fp_line
			(start 0 -1.27)
			(end 0 3.81)
			(stroke
				(width 0.1)
				(type default)
			)
			(layer "F.Fab")
		)
		(fp_line
			(start 2.54 -1.27)
			(end 0 -1.27)
			(stroke
				(width 0.1)
				(type default)
			)
			(layer "F.Fab")
		)
		(fp_poly
			(pts
				(xy -0.761746 0) (xy -2.285746 -0.762) (xy -2.285746 0.762)
			)
			(stroke
				(width 0)
				(type default)
			)
			(fill yes)
			(layer "F.Fab")
		)
		(pad "1" thru_hole circle
			(at 0 0 270)
			(size 1.0033 1.0033)
			(drill 0.249936)
			(layers "*.Cu" "*.Mask")
			(remove_unused_layers no)
			(net "TDR_DIFF_85_IN1_DP")
			(clearance 0.10795)
			(thermal_gap 0.10795)
			(padstack
				(mode front_inner_back)
				(layer "Inner"
					(shape circle)
					(size 0.8001 0.8001)
					(clearance 0.1524)
				)
				(layer "B.Cu"
					(shape circle)
					(size 1.0033 1.0033)
					(clearance 0.10795)
				)
			)
		)
		(pad "2" thru_hole circle
			(at 2.54 0 270)
			(size 1.9939 1.9939)
			(drill 0.249936)
			(layers "*.Cu" "*.Mask")
			(remove_unused_layers no)
			(net "T1_GND")
			(clearance 0.10795)
			(thermal_gap 0.10795)
			(padstack
				(mode front_inner_back)
				(layer "Inner"
					(shape circle)
					(size 0.8001 0.8001)
					(clearance 0.1524)
				)
				(layer "B.Cu"
					(shape circle)
					(size 1.9939 1.9939)
					(clearance 0.10795)
				)
			)
		)
		(pad "3" thru_hole circle
			(at 2.54 2.54 270)
			(size 1.9939 1.9939)
			(drill 0.249936)
			(layers "*.Cu" "*.Mask")
			(remove_unused_layers no)
			(net "T1_GND")
			(clearance 0.10795)
			(thermal_gap 0.10795)
			(padstack
				(mode front_inner_back)
				(layer "Inner"
					(shape circle)
					(size 0.8001 0.8001)
					(clearance 0.1524)
				)
				(layer "B.Cu"
					(shape circle)
					(size 1.9939 1.9939)
					(clearance 0.10795)
				)
			)
		)
		(pad "4" thru_hole circle
			(at 0 2.54 270)
			(size 1.0033 1.0033)
			(drill 0.249936)
			(layers "*.Cu" "*.Mask")
			(remove_unused_layers no)
			(net "TDR_DIFF_85_IN1_DN")
			(clearance 0.10795)
			(thermal_gap 0.10795)
			(padstack
				(mode front_inner_back)
				(layer "Inner"
					(shape circle)
					(size 0.8001 0.8001)
					(clearance 0.1524)
				)
				(layer "B.Cu"
					(shape circle)
					(size 1.0033 1.0033)
					(clearance 0.10795)
				)
			)
		)
	)
	(footprint ""
		(layer "F.Cu")
		(at 398.012412 -410.175456 90)
		(property "Reference" "C7036"
			(at 0 0 90)
			(layer "F.SilkS")
			(hide yes)
			(effects
				(font
					(size 1.27 1.27)
				)
			)
		)
		(property "Value" ""
			(at 0 0 90)
			(layer "F.Fab")
			(effects
				(font
					(size 1.27 1.27)
				)
			)
		)
		(duplicate_pad_numbers_are_jumpers no)
		(fp_line
			(start 1.524 -0.762)
			(end 1.524 0.762)
			(stroke
				(width 0.1524)
				(type default)
			)
			(layer "F.SilkS")
		)
		(fp_line
			(start -1.524 -0.762)
			(end 1.524 -0.762)
			(stroke
				(width 0.1524)
				(type default)
			)
			(layer "F.SilkS")
		)
		(fp_line
			(start 1.524 0.762)
			(end -1.524 0.762)
			(stroke
				(width 0.1524)
				(type default)
			)
			(layer "F.SilkS")
		)
		(fp_line
			(start -1.524 0.762)
			(end -1.524 -0.762)
			(stroke
				(width 0.1524)
				(type default)
			)
			(layer "F.SilkS")
		)
		(fp_line
			(start 1.1049 -0.724916)
			(end -1.1049 -0.724916)
			(stroke
				(width 0.1)
				(type default)
			)
			(layer "F.Fab")
		)
		(fp_line
			(start -1.1049 -0.724916)
			(end -1.1049 0.724916)
			(stroke
				(width 0.1)
				(type default)
			)
			(layer "F.Fab")
		)
		(fp_line
			(start 1.1049 0.724916)
			(end 1.1049 -0.724916)
			(stroke
				(width 0.1)
				(type default)
			)
			(layer "F.Fab")
		)
		(fp_line
			(start -1.1049 0.724916)
			(end 1.1049 0.724916)
			(stroke
				(width 0.1)
				(type default)
			)
			(layer "F.Fab")
		)
		(pad "1" smd rect
			(at -0.889 0 270)
			(size 1.016 1.27)
			(layers "F.Cu" "F.Mask" "F.Paste")
			(net "P0V9_CPU0_RT_2D")
		)
		(pad "2" smd rect
			(at 0.889 0 270)
			(size 1.016 1.27)
			(layers "F.Cu" "F.Mask" "F.Paste")
			(net "GND")
		)
	)
	(footprint ""
		(layer "F.Cu")
		(at 95.939102 -373.03583 -90)
		(property "Reference" "C719"
			(at 0 0 270)
			(layer "F.SilkS")
			(hide yes)
			(effects
				(font
					(size 1.27 1.27)
				)
			)
		)
		(property "Value" ""
			(at 0 0 270)
			(layer "F.Fab")
			(effects
				(font
					(size 1.27 1.27)
				)
			)
		)
		(duplicate_pad_numbers_are_jumpers no)
		(fp_line
			(start -0.299974 0.150114)
			(end -0.299974 -0.150114)
			(stroke
				(width 0.1)
				(type default)
			)
			(layer "F.Fab")
		)
		(fp_line
			(start 0.299974 0.150114)
			(end -0.299974 0.150114)
			(stroke
				(width 0.1)
				(type default)
			)
			(layer "F.Fab")
		)
		(fp_line
			(start -0.299974 -0.150114)
			(end 0.299974 -0.150114)
			(stroke
				(width 0.1)
				(type default)
			)
			(layer "F.Fab")
		)
		(fp_line
			(start 0.299974 -0.150114)
			(end 0.299974 0.150114)
			(stroke
				(width 0.1)
				(type default)
			)
			(layer "F.Fab")
		)
		(pad "1" smd rect
			(at -0.2667 0 270)
			(size 0.3048 0.381)
			(layers "F.Cu" "F.Mask" "F.Paste")
			(net "P5E_CPU1_P1_TX_C_DP<11>")
		)
		(pad "2" smd rect
			(at 0.2667 0 270)
			(size 0.3048 0.381)
			(layers "F.Cu" "F.Mask" "F.Paste")
			(net "P5E_CPU1_P1_TX_DP<11>")
		)
	)
	(footprint ""
		(layer "F.Cu")
		(at 369.146836 -323.466968 90)
		(property "Reference" "R1205"
			(at 0 0 90)
			(layer "F.SilkS")
			(hide yes)
			(effects
				(font
					(size 1.27 1.27)
				)
			)
		)
		(property "Value" ""
			(at 0 0 90)
			(layer "F.Fab")
			(effects
				(font
					(size 1.27 1.27)
				)
			)
		)
		(duplicate_pad_numbers_are_jumpers no)
		(fp_line
			(start 0.7874 -0.4064)
			(end 0.7874 0.4064)
			(stroke
				(width 0.1524)
				(type default)
			)
			(layer "F.SilkS")
		)
		(fp_line
			(start -0.7874 -0.4064)
			(end 0.7874 -0.4064)
			(stroke
				(width 0.1524)
				(type default)
			)
			(layer "F.SilkS")
		)
		(fp_line
			(start 0.7874 0.4064)
			(end -0.7874 0.4064)
			(stroke
				(width 0.1524)
				(type default)
			)
			(layer "F.SilkS")
		)
		(fp_line
			(start -0.7874 0.4064)
			(end -0.7874 -0.4064)
			(stroke
				(width 0.1524)
				(type default)
			)
			(layer "F.SilkS")
		)
		(fp_line
			(start -0.12065 -0.305054)
			(end -0.12065 -0.2794)
			(stroke
				(width 0.1)
				(type default)
			)
			(layer "F.Fab")
		)
		(fp_line
			(start -0.67945 -0.305054)
			(end -0.12065 -0.305054)
			(stroke
				(width 0.1)
				(type default)
			)
			(layer "F.Fab")
		)
		(fp_line
			(start 0.67945 -0.3048)
			(end 0.67945 0.3048)
			(stroke
				(width 0.1)
				(type default)
			)
			(layer "F.Fab")
		)
		(fp_line
			(start 0.12065 -0.3048)
			(end 0.67945 -0.3048)
			(stroke
				(width 0.1)
				(type default)
			)
			(layer "F.Fab")
		)
		(fp_line
			(start 0.12065 -0.2794)
			(end 0.12065 -0.3048)
			(stroke
				(width 0.1)
				(type default)
			)
			(layer "F.Fab")
		)
		(fp_line
			(start -0.12065 -0.2794)
			(end 0.12065 -0.2794)
			(stroke
				(width 0.1)
				(type default)
			)
			(layer "F.Fab")
		)
		(fp_line
			(start 0.120396 0.2794)
			(end -0.12065 0.2794)
			(stroke
				(width 0.1)
				(type default)
			)
			(layer "F.Fab")
		)
		(fp_line
			(start -0.12065 0.2794)
			(end -0.12065 0.3048)
			(stroke
				(width 0.1)
				(type default)
			)
			(layer "F.Fab")
		)
		(fp_line
			(start 0.67945 0.3048)
			(end 0.120396 0.3048)
			(stroke
				(width 0.1)
				(type default)
			)
			(layer "F.Fab")
		)
		(fp_line
			(start 0.120396 0.3048)
			(end 0.120396 0.2794)
			(stroke
				(width 0.1)
				(type default)
			)
			(layer "F.Fab")
		)
		(fp_line
			(start -0.12065 0.3048)
			(end -0.67945 0.3048)
			(stroke
				(width 0.1)
				(type default)
			)
			(layer "F.Fab")
		)
		(fp_line
			(start -0.67945 0.3048)
			(end -0.67945 -0.305054)
			(stroke
				(width 0.1)
				(type default)
			)
			(layer "F.Fab")
		)
		(pad "1" smd circle
			(at -0.40005 0 90)
			(size 0 0)
			(layers "F.Cu" "F.Mask" "F.Paste")
			(net "FM_PASSWORD_CLEAR_R_N")
		)
		(pad "2" smd circle
			(at 0.40005 0 90)
			(size 0 0)
			(layers "F.Cu" "F.Mask" "F.Paste")
			(net "FM_PASSWORD_CLEAR_N")
		)
	)
	(footprint ""
		(layer "F.Cu")
		(at 449.551806 -424.310556)
		(property "Reference" "PR6605"
			(at 0 0 0)
			(layer "F.SilkS")
			(hide yes)
			(effects
				(font
					(size 1.27 1.27)
				)
			)
		)
		(property "Value" ""
			(at 0 0 0)
			(layer "F.Fab")
			(effects
				(font
					(size 1.27 1.27)
				)
			)
		)
		(duplicate_pad_numbers_are_jumpers no)
		(fp_line
			(start -0.7874 -0.4064)
			(end 0.7874 -0.4064)
			(stroke
				(width 0.1524)
				(type default)
			)
			(layer "F.SilkS")
		)
		(fp_line
			(start -0.7874 0.4064)
			(end -0.7874 -0.4064)
			(stroke
				(width 0.1524)
				(type default)
			)
			(layer "F.SilkS")
		)
		(fp_line
			(start 0.7874 -0.4064)
			(end 0.7874 0.4064)
			(stroke
				(width 0.1524)
				(type default)
			)
			(layer "F.SilkS")
		)
		(fp_line
			(start 0.7874 0.4064)
			(end -0.7874 0.4064)
			(stroke
				(width 0.1524)
				(type default)
			)
			(layer "F.SilkS")
		)
		(fp_line
			(start -0.67945 -0.305054)
			(end -0.12065 -0.305054)
			(stroke
				(width 0.1)
				(type default)
			)
			(layer "F.Fab")
		)
		(fp_line
			(start -0.67945 0.3048)
			(end -0.67945 -0.305054)
			(stroke
				(width 0.1)
				(type default)
			)
			(layer "F.Fab")
		)
		(fp_line
			(start -0.12065 -0.305054)
			(end -0.12065 -0.2794)
			(stroke
				(width 0.1)
				(type default)
			)
			(layer "F.Fab")
		)
		(fp_line
			(start -0.12065 -0.2794)
			(end 0.12065 -0.2794)
			(stroke
				(width 0.1)
				(type default)
			)
			(layer "F.Fab")
		)
		(fp_line
			(start -0.12065 0.2794)
			(end -0.12065 0.3048)
			(stroke
				(width 0.1)
				(type default)
			)
			(layer "F.Fab")
		)
		(fp_line
			(start -0.12065 0.3048)
			(end -0.67945 0.3048)
			(stroke
				(width 0.1)
				(type default)
			)
			(layer "F.Fab")
		)
		(fp_line
			(start 0.120396 0.2794)
			(end -0.12065 0.2794)
			(stroke
				(width 0.1)
				(type default)
			)
			(layer "F.Fab")
		)
		(fp_line
			(start 0.120396 0.3048)
			(end 0.120396 0.2794)
			(stroke
				(width 0.1)
				(type default)
			)
			(layer "F.Fab")
		)
		(fp_line
			(start 0.12065 -0.3048)
			(end 0.67945 -0.3048)
			(stroke
				(width 0.1)
				(type default)
			)
			(layer "F.Fab")
		)
		(fp_line
			(start 0.12065 -0.2794)
			(end 0.12065 -0.3048)
			(stroke
				(width 0.1)
				(type default)
			)
			(layer "F.Fab")
		)
		(fp_line
			(start 0.67945 -0.3048)
			(end 0.67945 0.3048)
			(stroke
				(width 0.1)
				(type default)
			)
			(layer "F.Fab")
		)
		(fp_line
			(start 0.67945 0.3048)
			(end 0.120396 0.3048)
			(stroke
				(width 0.1)
				(type default)
			)
			(layer "F.Fab")
		)
		(pad "1" smd circle
			(at -0.40005 0)
			(size 0 0)
			(layers "F.Cu" "F.Mask" "F.Paste")
			(net "P0V9_RETIMER_CPU0_VMON")
		)
		(pad "2" smd circle
			(at 0.40005 0)
			(size 0 0)
			(layers "F.Cu" "F.Mask" "F.Paste")
			(net "GND")
		)
	)
	(footprint ""
		(layer "F.Cu")
		(at 91.313 -78.105)
		(property "Reference" "R1163"
			(at 0 0 0)
			(layer "F.SilkS")
			(hide yes)
			(effects
				(font
					(size 1.27 1.27)
				)
			)
		)
		(property "Value" ""
			(at 0 0 0)
			(layer "F.Fab")
			(effects
				(font
					(size 1.27 1.27)
				)
			)
		)
		(duplicate_pad_numbers_are_jumpers no)
		(fp_line
			(start -0.7874 -0.4064)
			(end 0.7874 -0.4064)
			(stroke
				(width 0.1524)
				(type default)
			)
			(layer "F.SilkS")
		)
		(fp_line
			(start -0.7874 0.4064)
			(end -0.7874 -0.4064)
			(stroke
				(width 0.1524)
				(type default)
			)
			(layer "F.SilkS")
		)
		(fp_line
			(start 0.7874 -0.4064)
			(end 0.7874 0.4064)
			(stroke
				(width 0.1524)
				(type default)
			)
			(layer "F.SilkS")
		)
		(fp_line
			(start 0.7874 0.4064)
			(end -0.7874 0.4064)
			(stroke
				(width 0.1524)
				(type default)
			)
			(layer "F.SilkS")
		)
		(fp_line
			(start -0.67945 -0.305054)
			(end -0.12065 -0.305054)
			(stroke
				(width 0.1)
				(type default)
			)
			(layer "F.Fab")
		)
		(fp_line
			(start -0.67945 0.3048)
			(end -0.67945 -0.305054)
			(stroke
				(width 0.1)
				(type default)
			)
			(layer "F.Fab")
		)
		(fp_line
			(start -0.12065 -0.305054)
			(end -0.12065 -0.2794)
			(stroke
				(width 0.1)
				(type default)
			)
			(layer "F.Fab")
		)
		(fp_line
			(start -0.12065 -0.2794)
			(end 0.12065 -0.2794)
			(stroke
				(width 0.1)
				(type default)
			)
			(layer "F.Fab")
		)
		(fp_line
			(start -0.12065 0.2794)
			(end -0.12065 0.3048)
			(stroke
				(width 0.1)
				(type default)
			)
			(layer "F.Fab")
		)
		(fp_line
			(start -0.12065 0.3048)
			(end -0.67945 0.3048)
			(stroke
				(width 0.1)
				(type default)
			)
			(layer "F.Fab")
		)
		(fp_line
			(start 0.120396 0.2794)
			(end -0.12065 0.2794)
			(stroke
				(width 0.1)
				(type default)
			)
			(layer "F.Fab")
		)
		(fp_line
			(start 0.120396 0.3048)
			(end 0.120396 0.2794)
			(stroke
				(width 0.1)
				(type default)
			)
			(layer "F.Fab")
		)
		(fp_line
			(start 0.12065 -0.3048)
			(end 0.67945 -0.3048)
			(stroke
				(width 0.1)
				(type default)
			)
			(layer "F.Fab")
		)
		(fp_line
			(start 0.12065 -0.2794)
			(end 0.12065 -0.3048)
			(stroke
				(width 0.1)
				(type default)
			)
			(layer "F.Fab")
		)
		(fp_line
			(start 0.67945 -0.3048)
			(end 0.67945 0.3048)
			(stroke
				(width 0.1)
				(type default)
			)
			(layer "F.Fab")
		)
		(fp_line
			(start 0.67945 0.3048)
			(end 0.120396 0.3048)
			(stroke
				(width 0.1)
				(type default)
			)
			(layer "F.Fab")
		)
		(pad "1" smd circle
			(at -0.40005 0)
			(size 0 0)
			(layers "F.Cu" "F.Mask" "F.Paste")
			(net "HP_LVC3_OCP_V3_2_P12V_PWRGD")
		)
		(pad "2" smd circle
			(at 0.40005 0)
			(size 0 0)
			(layers "F.Cu" "F.Mask" "F.Paste")
			(net "HP_LVC3_OCP_V3_2_P12V_R_PWRGD")
		)
	)
)
